# T6G (Grand Teton) — schematic netlist excerpt (pin names and nets, part order shuffled) for the footprints in the layout excerpt that follows; sources: Cadence DE-HDL packaged netlist, KiCad conversion of 04192023_DAF0TMB3IC0_F0TG_MB_C_brd_V02_OCP.brd

C2284  Q_CAP  22UF 4V 20% X6S  pkg C0402  page 72 : A = PVDDCR_SOC_P1 ; B = GND
C1924  Q_CAP  0.1UF 25V 10% X7R  pkg 0402  page 144 : A = P3V3_M2_0 ; B = GND

(kicad_pcb
	(version 20260206)
	(generator "pcbnew")
	(generator_version "10.0")
	(general
		(thickness 1.6)
		(legacy_teardrops no)
	)
	(paper "A4")
	(title_block
		(title "04192023_DAF0TMB3IC0_F0TG_MB_C_brd_V02_OCP.brd")
		(comment 1 "Grand Teton / footprints 7803-7804 of 8354")
	)
	(layers
		(0 "F.Cu" signal "TOP")
		(4 "In1.Cu" signal "GND")
		(6 "In2.Cu" signal "IN1")
		(8 "In3.Cu" signal "GND1")
		(10 "In4.Cu" signal "IN2")
		(12 "In5.Cu" signal "GND2")
		(14 "In6.Cu" signal "IN3")
		(16 "In7.Cu" signal "GND3")
		(18 "In8.Cu" signal "VCC")
		(20 "In9.Cu" signal "VCC1")
		(22 "In10.Cu" signal "GND4")
		(24 "In11.Cu" signal "IN4")
		(26 "In12.Cu" signal "GND5")
		(28 "In13.Cu" signal "IN5")
		(30 "In14.Cu" signal "GND6")
		(32 "In15.Cu" signal "IN6")
		(34 "In16.Cu" signal "GND7")
		(2 "B.Cu" signal "BOTTOM")
		(9 "F.Adhes" user "F.Adhesive")
		(11 "B.Adhes" user "B.Adhesive")
		(13 "F.Paste" user "Package Geometry/Pastemask Top")
		(15 "B.Paste" user "Package Geometry/Pastemask Bottom")
		(5 "F.SilkS" user "Ref Des/Silkscreen Top")
		(7 "B.SilkS" user "Ref Des/Silkscreen Bottom")
		(1 "F.Mask" user "Board Geometry/Soldermask Top")
		(3 "B.Mask" user "Board Geometry/Soldermask Bottom")
		(17 "Dwgs.User" user "User.Drawings")
		(19 "Cmts.User" user "User.Comments")
		(21 "Eco1.User" user "User.Eco1")
		(23 "Eco2.User" user "User.Eco2")
		(25 "Edge.Cuts" user "Board Geometry/Outline")
		(27 "Margin" user)
		(31 "F.CrtYd" user "Package Geometry/Place Bound Top")
		(29 "B.CrtYd" user "Package Geometry/Place Bound Bottom")
		(35 "F.Fab" user "Ref Des/Assembly Top")
		(33 "B.Fab" user "Ref Des/Assembly Bottom")
	)
	(footprint ""
		(layer "B.Cu")
		(at 113.705386 -253.432564)
		(property "Reference" "C2284"
			(at 0 0 0)
			(layer "B.SilkS")
			(hide yes)
			(effects
				(font
					(size 1.27 1.27)
				)
				(justify mirror)
			)
		)
		(property "Value" ""
			(at 0 0 0)
			(layer "B.Fab")
			(effects
				(font
					(size 1.27 1.27)
				)
				(justify mirror)
			)
		)
		(duplicate_pad_numbers_are_jumpers no)
		(fp_line
			(start -0.7874 -0.4064)
			(end -0.7874 0.4064)
			(stroke
				(width 0.1524)
				(type default)
			)
			(layer "B.SilkS")
		)
		(fp_line
			(start -0.7874 0.4064)
			(end 0.7874 0.4064)
			(stroke
				(width 0.1524)
				(type default)
			)
			(layer "B.SilkS")
		)
		(fp_line
			(start 0.7874 -0.4064)
			(end -0.7874 -0.4064)
			(stroke
				(width 0.1524)
				(type default)
			)
			(layer "B.SilkS")
		)
		(fp_line
			(start 0.7874 0.4064)
			(end 0.7874 -0.4064)
			(stroke
				(width 0.1524)
				(type default)
			)
			(layer "B.SilkS")
		)
		(fp_line
			(start -0.67945 -0.3048)
			(end -0.67945 0.3048)
			(stroke
				(width 0.1)
				(type default)
			)
			(layer "B.Fab")
		)
		(fp_line
			(start -0.67945 0.3048)
			(end -0.120396 0.3048)
			(stroke
				(width 0.1)
				(type default)
			)
			(layer "B.Fab")
		)
		(fp_line
			(start -0.12065 -0.3048)
			(end -0.67945 -0.3048)
			(stroke
				(width 0.1)
				(type default)
			)
			(layer "B.Fab")
		)
		(fp_line
			(start -0.12065 -0.2794)
			(end -0.12065 -0.3048)
			(stroke
				(width 0.1)
				(type default)
			)
			(layer "B.Fab")
		)
		(fp_line
			(start -0.120396 0.2794)
			(end 0.12065 0.2794)
			(stroke
				(width 0.1)
				(type default)
			)
			(layer "B.Fab")
		)
		(fp_line
			(start -0.120396 0.3048)
			(end -0.120396 0.2794)
			(stroke
				(width 0.1)
				(type default)
			)
			(layer "B.Fab")
		)
		(fp_line
			(start 0.12065 -0.305054)
			(end 0.12065 -0.2794)
			(stroke
				(width 0.1)
				(type default)
			)
			(layer "B.Fab")
		)
		(fp_line
			(start 0.12065 -0.2794)
			(end -0.12065 -0.2794)
			(stroke
				(width 0.1)
				(type default)
			)
			(layer "B.Fab")
		)
		(fp_line
			(start 0.12065 0.2794)
			(end 0.12065 0.3048)
			(stroke
				(width 0.1)
				(type default)
			)
			(layer "B.Fab")
		)
		(fp_line
			(start 0.12065 0.3048)
			(end 0.67945 0.3048)
			(stroke
				(width 0.1)
				(type default)
			)
			(layer "B.Fab")
		)
		(fp_line
			(start 0.67945 -0.305054)
			(end 0.12065 -0.305054)
			(stroke
				(width 0.1)
				(type default)
			)
			(layer "B.Fab")
		)
		(fp_line
			(start 0.67945 0.3048)
			(end 0.67945 -0.305054)
			(stroke
				(width 0.1)
				(type default)
			)
			(layer "B.Fab")
		)
		(pad "1" smd circle
			(at 0.40005 0 180)
			(size 0 0)
			(layers "B.Cu" "B.Mask" "B.Paste")
			(net "PVDDCR_SOC_P1")
		)
		(pad "2" smd circle
			(at -0.40005 0 180)
			(size 0 0)
			(layers "B.Cu" "B.Mask" "B.Paste")
			(net "GND")
		)
	)
	(footprint ""
		(layer "B.Cu")
		(at 169.66692 -52.415948 180)
		(property "Reference" "C1924"
			(at 0 0 0)
			(layer "B.SilkS")
			(hide yes)
			(effects
				(font
					(size 1.27 1.27)
				)
				(justify mirror)
			)
		)
		(property "Value" ""
			(at 0 0 0)
			(layer "B.Fab")
			(effects
				(font
					(size 1.27 1.27)
				)
				(justify mirror)
			)
		)
		(duplicate_pad_numbers_are_jumpers no)
		(fp_line
			(start 0.7874 0.4064)
			(end 0.7874 -0.4064)
			(stroke
				(width 0.1524)
				(type default)
			)
			(layer "B.SilkS")
		)
		(fp_line
			(start 0.7874 -0.4064)
			(end -0.7874 -0.4064)
			(stroke
				(width 0.1524)
				(type default)
			)
			(layer "B.SilkS")
		)
		(fp_line
			(start -0.7874 0.4064)
			(end 0.7874 0.4064)
			(stroke
				(width 0.1524)
				(type default)
			)
			(layer "B.SilkS")
		)
		(fp_line
			(start -0.7874 -0.4064)
			(end -0.7874 0.4064)
			(stroke
				(width 0.1524)
				(type default)
			)
			(layer "B.SilkS")
		)
		(fp_line
			(start 0.67945 0.3048)
			(end 0.67945 -0.305054)
			(stroke
				(width 0.1)
				(type default)
			)
			(layer "B.Fab")
		)
		(fp_line
			(start 0.67945 -0.305054)
			(end 0.12065 -0.305054)
			(stroke
				(width 0.1)
				(type default)
			)
			(layer "B.Fab")
		)
		(fp_line
			(start 0.12065 0.3048)
			(end 0.67945 0.3048)
			(stroke
				(width 0.1)
				(type default)
			)
			(layer "B.Fab")
		)
		(fp_line
			(start 0.12065 0.2794)
			(end 0.12065 0.3048)
			(stroke
				(width 0.1)
				(type default)
			)
			(layer "B.Fab")
		)
		(fp_line
			(start 0.12065 -0.2794)
			(end -0.12065 -0.2794)
			(stroke
				(width 0.1)
				(type default)
			)
			(layer "B.Fab")
		)
		(fp_line
			(start 0.12065 -0.305054)
			(end 0.12065 -0.2794)
			(stroke
				(width 0.1)
				(type default)
			)
			(layer "B.Fab")
		)
		(fp_line
			(start -0.120396 0.3048)
			(end -0.120396 0.2794)
			(stroke
				(width 0.1)
				(type default)
			)
			(layer "B.Fab")
		)
		(fp_line
			(start -0.120396 0.2794)
			(end 0.12065 0.2794)
			(stroke
				(width 0.1)
				(type default)
			)
			(layer "B.Fab")
		)
		(fp_line
			(start -0.12065 -0.2794)
			(end -0.12065 -0.3048)
			(stroke
				(width 0.1)
				(type default)
			)
			(layer "B.Fab")
		)
		(fp_line
			(start -0.12065 -0.3048)
			(end -0.67945 -0.3048)
			(stroke
				(width 0.1)
				(type default)
			)
			(layer "B.Fab")
		)
		(fp_line
			(start -0.67945 0.3048)
			(end -0.120396 0.3048)
			(stroke
				(width 0.1)
				(type default)
			)
			(layer "B.Fab")
		)
		(fp_line
			(start -0.67945 -0.3048)
			(end -0.67945 0.3048)
			(stroke
				(width 0.1)
				(type default)
			)
			(layer "B.Fab")
		)
		(pad "1" smd circle
			(at 0.40005 0)
			(size 0 0)
			(layers "B.Cu" "B.Mask" "B.Paste")
			(net "P3V3_M2_0")
		)
		(pad "2" smd circle
			(at -0.40005 0)
			(size 0 0)
			(layers "B.Cu" "B.Mask" "B.Paste")
			(net "GND")
		)
	)
)
